# TIMECARD (Time Appliance Project (Time Card)) — schematic netlist excerpt (pin names and nets, part order shuffled) for the footprints in the layout excerpt that follows; sources: Cadence DE-HDL packaged netlist, KiCad conversion of R4006-B0001-02_R01.brd

C115  CAPACITOR  0.1UF 10V 10%  pkg SMC_0402R_H022  page 14 : \1\ = XP3R3V_FPGA ; \2\ = SG
R28  RESISTOR  0OHM -  pkg SMC_0402R_H016  page 9 : \1\ = PCIE_CONN_TCK ; \2\ = FPGA_TCK

(kicad_pcb
	(version 20260206)
	(generator "pcbnew")
	(generator_version "10.0")
	(general
		(thickness 1.6)
		(legacy_teardrops no)
	)
	(paper "A4")
	(title_block
		(title "timecard-production-celestica-r4006 — R4006-B0001-02_R01.brd")
		(comment 1 "Time Appliance Project (Time Card) / footprints 1093-1094 of 1113")
	)
	(layers
		(0 "F.Cu" signal "TOP")
		(4 "In1.Cu" signal "L02_GND1")
		(6 "In2.Cu" signal "L03_SIG1")
		(8 "In3.Cu" signal "L04_GND2")
		(10 "In4.Cu" signal "L05_VCC1")
		(12 "In5.Cu" signal "L06_VCC2")
		(14 "In6.Cu" signal "L07_GND3")
		(16 "In7.Cu" signal "L08_SIG2")
		(18 "In8.Cu" signal "L09_GND4")
		(2 "B.Cu" signal "BOTTOM")
		(9 "F.Adhes" user "F.Adhesive")
		(11 "B.Adhes" user "B.Adhesive")
		(13 "F.Paste" user "Package Geometry/Pastemask Top")
		(15 "B.Paste" user "Package Geometry/Pastemask Bottom")
		(5 "F.SilkS" user "Ref Des/Silkscreen Top")
		(7 "B.SilkS" user "Ref Des/Silkscreen Bottom")
		(1 "F.Mask" user "Board Geometry/Soldermask Top")
		(3 "B.Mask" user "Board Geometry/Soldermask Bottom")
		(17 "Dwgs.User" user "User.Drawings")
		(19 "Cmts.User" user "User.Comments")
		(21 "Eco1.User" user "User.Eco1")
		(23 "Eco2.User" user "User.Eco2")
		(25 "Edge.Cuts" user "Board Geometry/Outline")
		(27 "Margin" user)
		(31 "F.CrtYd" user "Package Geometry/Place Bound Top")
		(29 "B.CrtYd" user "Package Geometry/Place Bound Bottom")
		(35 "F.Fab" user "Ref Des/Assembly Top")
		(33 "B.Fab" user "Ref Des/Assembly Bottom")
	)
	(footprint ""
		(layer "B.Cu")
		(at 140.335 -65.913)
		(property "Reference" "R28"
			(at 1.73863 0.381 270)
			(unlocked yes)
			(layer "B.SilkS")
			(effects
				(font
					(size 0.7874 0.5842)
					(thickness 0.1524)
				)
				(justify mirror)
			)
		)
		(property "Value" "VAL*"
			(at -0.02032 2.13233 0)
			(unlocked yes)
			(layer "B.Fab")
			(hide yes)
			(effects
				(font
					(size 0.7874 0.5842)
					(thickness 0.1524)
				)
				(justify mirror)
			)
		)
		(property "Tolerance" "TOL*"
			(at -0.044704 3.05435 0)
			(unlocked yes)
			(layer "Cmts.User")
			(hide yes)
			(effects
				(font
					(size 0.7874 0.5842)
					(thickness 0.1524)
				)
				(justify mirror)
			)
		)
		(property "User Part Number" "PARTNUM*"
			(at -0.02032 4.024884 0)
			(unlocked yes)
			(layer "Cmts.User")
			(hide yes)
			(effects
				(font
					(size 0.7874 0.5842)
					(thickness 0.1524)
				)
				(justify mirror)
			)
		)
		(property "Device Type" "RESISTOR-G155-100R0-J0,0OHM,-"
			(at -0.008382 1.210564 0)
			(unlocked yes)
			(layer "B.Fab")
			(hide yes)
			(effects
				(font
					(size 0.7874 0.5842)
					(thickness 0.1524)
				)
				(justify mirror)
			)
		)
		(duplicate_pad_numbers_are_jumpers no)
		(fp_line
			(start -1.143 -0.5588)
			(end 1.143 -0.5588)
			(stroke
				(width 0.1)
				(type default)
			)
			(layer "B.SilkS")
		)
		(fp_line
			(start -1.143 0.5588)
			(end -1.143 -0.5588)
			(stroke
				(width 0.1)
				(type default)
			)
			(layer "B.SilkS")
		)
		(fp_line
			(start 1.143 -0.5588)
			(end 1.143 0.5588)
			(stroke
				(width 0.1)
				(type default)
			)
			(layer "B.SilkS")
		)
		(fp_line
			(start 1.143 0.5588)
			(end -1.143 0.5588)
			(stroke
				(width 0.1)
				(type default)
			)
			(layer "B.SilkS")
		)
		(fp_rect
			(start 1.143 0.5588)
			(end -1.143 -0.5588)
			(stroke
				(width 0)
				(type default)
			)
			(fill no)
			(layer "B.CrtYd")
		)
		(fp_line
			(start -0.508 -0.3048)
			(end 0.508 -0.3048)
			(stroke
				(width 0.1)
				(type default)
			)
			(layer "B.Fab")
		)
		(fp_line
			(start -0.508 0.3048)
			(end -0.508 -0.3048)
			(stroke
				(width 0.1)
				(type default)
			)
			(layer "B.Fab")
		)
		(fp_line
			(start 0.508 -0.3048)
			(end 0.508 0.3048)
			(stroke
				(width 0.1)
				(type default)
			)
			(layer "B.Fab")
		)
		(fp_line
			(start 0.508 0.3048)
			(end -0.508 0.3048)
			(stroke
				(width 0.1)
				(type default)
			)
			(layer "B.Fab")
		)
		(pad "1" smd rect
			(at 0.5334 0 180)
			(size 0.7112 0.6096)
			(layers "B.Cu" "B.Mask" "B.Paste")
			(net "PCIE_CONN_TCK")
		)
		(pad "2" smd rect
			(at -0.5334 0 180)
			(size 0.7112 0.6096)
			(layers "B.Cu" "B.Mask" "B.Paste")
			(net "FPGA_TCK")
		)
		(zone
			(layer "B.Cu")
			(hatch none 0.5)
			(connect_pads
				(clearance 0)
			)
			(min_thickness 0.25)
			(keepout
				(tracks allowed)
				(vias not_allowed)
				(pads allowed)
				(copperpour not_allowed)
				(footprints allowed)
			)
			(placement
				(enabled no)
				(sheetname "")
			)
			(fill
				(thermal_gap 0.5)
				(thermal_bridge_width 0.5)
				(island_removal_mode 0)
			)
			(polygon
				(pts
					(xy 140.4112 -65.6082) (xy 140.4112 -66.2178) (xy 140.2588 -66.2178) (xy 140.2588 -65.6082)
				)
			)
		)
	)
	(footprint ""
		(layer "B.Cu")
		(at 109.3724 -46.1264 90)
		(property "Reference" "C115"
			(at -1.6764 -42.98315 270)
			(unlocked yes)
			(layer "B.SilkS")
			(effects
				(font
					(size 0.635 0.4064)
					(thickness 0.1524)
				)
				(justify mirror)
			)
		)
		(property "Value" "VAL*"
			(at -0.0762 2.067306 90)
			(unlocked yes)
			(layer "B.Fab")
			(hide yes)
			(effects
				(font
					(size 0.7874 0.5842)
					(thickness 0.1524)
				)
				(justify mirror)
			)
		)
		(property "Device Type" "CAPACITOR-G105-0B104-CK,0.1UF,A"
			(at -0.0508 1.127506 90)
			(unlocked yes)
			(layer "B.Fab")
			(hide yes)
			(effects
				(font
					(size 0.7874 0.5842)
					(thickness 0.1524)
				)
				(justify mirror)
			)
		)
		(property "User Part Number" "PARTNUM*"
			(at -0.1016 4.023106 90)
			(unlocked yes)
			(layer "Cmts.User")
			(hide yes)
			(effects
				(font
					(size 0.7874 0.5842)
					(thickness 0.1524)
				)
				(justify mirror)
			)
		)
		(property "Tolerance" "TOL*"
			(at -0.0762 3.032506 90)
			(unlocked yes)
			(layer "Cmts.User")
			(hide yes)
			(effects
				(font
					(size 0.7874 0.5842)
					(thickness 0.1524)
				)
				(justify mirror)
			)
		)
		(duplicate_pad_numbers_are_jumpers no)
		(fp_line
			(start 1.143 -0.5588)
			(end 1.143 0.5588)
			(stroke
				(width 0.1)
				(type default)
			)
			(layer "B.SilkS")
		)
		(fp_line
			(start -1.143 -0.5588)
			(end 1.143 -0.5588)
			(stroke
				(width 0.1)
				(type default)
			)
			(layer "B.SilkS")
		)
		(fp_line
			(start 1.143 0.5588)
			(end -1.143 0.5588)
			(stroke
				(width 0.1)
				(type default)
			)
			(layer "B.SilkS")
		)
		(fp_line
			(start -1.143 0.5588)
			(end -1.143 -0.5588)
			(stroke
				(width 0.1)
				(type default)
			)
			(layer "B.SilkS")
		)
		(fp_poly
			(pts
				(xy 1.143 0.5588) (xy -1.143 0.5588) (xy -1.143 -0.5588) (xy 1.143 -0.5588)
			)
			(stroke
				(width 0)
				(type default)
			)
			(fill no)
			(layer "B.CrtYd")
		)
		(fp_line
			(start 0.508 -0.3048)
			(end 0.508 0.3048)
			(stroke
				(width 0.1)
				(type default)
			)
			(layer "B.Fab")
		)
		(fp_line
			(start -0.508 -0.3048)
			(end 0.508 -0.3048)
			(stroke
				(width 0.1)
				(type default)
			)
			(layer "B.Fab")
		)
		(fp_line
			(start 0.508 0.3048)
			(end -0.508 0.3048)
			(stroke
				(width 0.1)
				(type default)
			)
			(layer "B.Fab")
		)
		(fp_line
			(start -0.508 0.3048)
			(end -0.508 -0.3048)
			(stroke
				(width 0.1)
				(type default)
			)
			(layer "B.Fab")
		)
		(pad "1" smd rect
			(at 0.5334 0 270)
			(size 0.7112 0.6096)
			(layers "B.Cu" "B.Mask" "B.Paste")
			(net "XP3R3V_FPGA")
		)
		(pad "2" smd rect
			(at -0.5334 0 270)
			(size 0.7112 0.6096)
			(layers "B.Cu" "B.Mask" "B.Paste")
			(net "SG")
		)
		(zone
			(layer "B.Cu")
			(hatch none 0.5)
			(connect_pads
				(clearance 0)
			)
			(min_thickness 0.25)
			(keepout
				(tracks not_allowed)
				(vias allowed)
				(pads allowed)
				(copperpour not_allowed)
				(footprints allowed)
			)
			(placement
				(enabled no)
				(sheetname "")
			)
			(fill
				(thermal_gap 0.5)
				(thermal_bridge_width 0.5)
				(island_removal_mode 0)
			)
			(polygon
				(pts
					(xy 109.6772 -46.2026) (xy 109.0676 -46.2026) (xy 109.0676 -46.0502) (xy 109.6772 -46.0502)
				)
			)
		)
		(zone
			(layer "B.Cu")
			(hatch none 0.5)
			(connect_pads
				(clearance 0)
			)
			(min_thickness 0.25)
			(keepout
				(tracks allowed)
				(vias not_allowed)
				(pads allowed)
				(copperpour not_allowed)
				(footprints allowed)
			)
			(placement
				(enabled no)
				(sheetname "")
			)
			(fill
				(thermal_gap 0.5)
				(thermal_bridge_width 0.5)
				(island_removal_mode 0)
			)
			(polygon
				(pts
					(xy 109.6772 -46.2026) (xy 109.0676 -46.2026) (xy 109.0676 -46.0502) (xy 109.6772 -46.0502)
				)
			)
		)
	)
)
